# BASEBOARD_FAB2 (Tioga Pass) — schematic netlist excerpt (pin names and nets, part order shuffled) for the footprints in the layout excerpt that follows; sources: Cadence DE-HDL packaged netlist, KiCad conversion of Wiwynn_Tioga_Pass_MB.brd

R1L8  RES  470.0 5% CHIP  pkg 0402  page 175 : A = P5V_STBY ; B = FP_ID_LED_XOR_R
R8F16  RES  4.75K 1% EMPTY  pkg 0402  page 162 : A = P3V3_STBY ; B = PU_SPI_FLASH_RESET_2_N
R1T34  RES  0 5.0% CHIP  pkg 0603  page 139 : A = P3V3_STBY ; B = P3V3_STBY_P1V5_LAN_I210

(kicad_pcb
	(version 20260206)
	(generator "pcbnew")
	(generator_version "10.0")
	(general
		(thickness 1.6)
		(legacy_teardrops no)
	)
	(paper "A4")
	(title_block
		(title "Wiwynn_Tioga_Pass_MB.brd")
		(comment 1 "Tioga Pass / footprints 3456-3458 of 4770")
	)
	(layers
		(0 "F.Cu" signal "TOP")
		(4 "In1.Cu" signal "L2GND")
		(6 "In2.Cu" signal "L3")
		(8 "In3.Cu" signal "L4GND")
		(10 "In4.Cu" signal "L5")
		(12 "In5.Cu" signal "L6GND")
		(14 "In6.Cu" signal "L7VCC")
		(16 "In7.Cu" signal "L8VCC")
		(18 "In8.Cu" signal "L9GND")
		(20 "In9.Cu" signal "L10")
		(22 "In10.Cu" signal "L11GND")
		(24 "In11.Cu" signal "L12")
		(26 "In12.Cu" signal "L13GND")
		(2 "B.Cu" signal "BOTTOM")
		(9 "F.Adhes" user "F.Adhesive")
		(11 "B.Adhes" user "B.Adhesive")
		(13 "F.Paste" user "Package Geometry/Pastemask Top")
		(15 "B.Paste" user "Package Geometry/Pastemask Bottom")
		(5 "F.SilkS" user "Ref Des/Silkscreen Top")
		(7 "B.SilkS" user "Ref Des/Silkscreen Bottom")
		(1 "F.Mask" user "Board Geometry/Soldermask Top")
		(3 "B.Mask" user "Board Geometry/Soldermask Bottom")
		(17 "Dwgs.User" user "User.Drawings")
		(19 "Cmts.User" user "User.Comments")
		(21 "Eco1.User" user "User.Eco1")
		(23 "Eco2.User" user "User.Eco2")
		(25 "Edge.Cuts" user "Board Geometry/Outline")
		(27 "Margin" user)
		(31 "F.CrtYd" user "Package Geometry/Place Bound Top")
		(29 "B.CrtYd" user "Package Geometry/Place Bound Bottom")
		(35 "F.Fab" user "Ref Des/Assembly Top")
		(33 "B.Fab" user "Ref Des/Assembly Bottom")
	)
	(footprint ""
		(layer "B.Cu")
		(at 367.157 -39.8272)
		(property "Reference" "R8F16"
			(at 0 0 0)
			(layer "B.SilkS")
			(hide yes)
			(effects
				(font
					(size 1.27 1.27)
				)
				(justify mirror)
			)
		)
		(property "Value" ""
			(at 0 0 0)
			(layer "B.Fab")
			(effects
				(font
					(size 1.27 1.27)
				)
				(justify mirror)
			)
		)
		(duplicate_pad_numbers_are_jumpers no)
		(fp_poly
			(pts
				(xy 0.2794 -0.1016) (xy -0.2794 -0.1016) (xy -0.2794 0.9906) (xy 0.2794 0.9906)
			)
			(stroke
				(width 0)
				(type default)
			)
			(fill no)
			(layer "B.CrtYd")
		)
		(fp_line
			(start -0.2794 -0.1016)
			(end 0.2794 -0.1016)
			(stroke
				(width 0.1)
				(type default)
			)
			(layer "B.Fab")
		)
		(fp_line
			(start -0.2794 0.9906)
			(end -0.2794 -0.1016)
			(stroke
				(width 0.1)
				(type default)
			)
			(layer "B.Fab")
		)
		(fp_line
			(start 0.2794 -0.1016)
			(end 0.2794 0.9906)
			(stroke
				(width 0.1)
				(type default)
			)
			(layer "B.Fab")
		)
		(fp_line
			(start 0.2794 0.9906)
			(end -0.2794 0.9906)
			(stroke
				(width 0.1)
				(type default)
			)
			(layer "B.Fab")
		)
		(pad "1" smd rect
			(at 0 0 180)
			(size 0.508 0.508)
			(layers "B.Cu" "B.Mask" "B.Paste")
			(net "P3V3_STBY")
		)
		(pad "2" smd rect
			(at 0 0.889 180)
			(size 0.508 0.508)
			(layers "B.Cu" "B.Mask" "B.Paste")
			(net "PU_SPI_FLASH_RESET_2_N")
		)
		(zone
			(layer "B.Cu")
			(hatch none 0.5)
			(connect_pads
				(clearance 0)
			)
			(min_thickness 0.25)
			(keepout
				(tracks allowed)
				(vias not_allowed)
				(pads allowed)
				(copperpour not_allowed)
				(footprints allowed)
			)
			(placement
				(enabled no)
				(sheetname "")
			)
			(fill
				(thermal_gap 0.5)
				(thermal_bridge_width 0.5)
				(island_removal_mode 0)
			)
			(polygon
				(pts
					(xy 367.411 -39.5732) (xy 366.903 -39.5732) (xy 366.903 -39.1922) (xy 367.411 -39.1922)
				)
			)
		)
		(zone
			(layer "B.Cu")
			(hatch none 0.5)
			(connect_pads
				(clearance 0)
			)
			(min_thickness 0.25)
			(keepout
				(tracks not_allowed)
				(vias allowed)
				(pads allowed)
				(copperpour not_allowed)
				(footprints allowed)
			)
			(placement
				(enabled no)
				(sheetname "")
			)
			(fill
				(thermal_gap 0.5)
				(thermal_bridge_width 0.5)
				(island_removal_mode 0)
			)
			(polygon
				(pts
					(xy 367.411 -39.1922) (xy 366.903 -39.1922) (xy 366.903 -39.5732) (xy 367.411 -39.5732)
				)
			)
		)
	)
	(footprint ""
		(layer "B.Cu")
		(at 476.4151 -36.2712 90)
		(property "Reference" "R1T34"
			(at 0 0 90)
			(layer "B.SilkS")
			(hide yes)
			(effects
				(font
					(size 1.27 1.27)
				)
				(justify mirror)
			)
		)
		(property "Value" ""
			(at 0 0 90)
			(layer "B.Fab")
			(effects
				(font
					(size 1.27 1.27)
				)
				(justify mirror)
			)
		)
		(duplicate_pad_numbers_are_jumpers no)
		(fp_poly
			(pts
				(xy 0.4953 -0.2032) (xy -0.4953 -0.2032) (xy -0.4953 1.6002) (xy 0.4953 1.6002)
			)
			(stroke
				(width 0)
				(type default)
			)
			(fill no)
			(layer "B.CrtYd")
		)
		(fp_line
			(start 0.4953 -0.2032)
			(end -0.4953 -0.2032)
			(stroke
				(width 0.1)
				(type default)
			)
			(layer "B.Fab")
		)
		(fp_line
			(start -0.4953 -0.2032)
			(end -0.4953 1.6002)
			(stroke
				(width 0.1)
				(type default)
			)
			(layer "B.Fab")
		)
		(fp_line
			(start 0.4953 1.6002)
			(end 0.4953 -0.2032)
			(stroke
				(width 0.1)
				(type default)
			)
			(layer "B.Fab")
		)
		(fp_line
			(start -0.4953 1.6002)
			(end 0.4953 1.6002)
			(stroke
				(width 0.1)
				(type default)
			)
			(layer "B.Fab")
		)
		(pad "1" smd rect
			(at 0 0 270)
			(size 0.762 0.889)
			(layers "B.Cu" "B.Mask" "B.Paste")
			(net "P3V3_STBY")
		)
		(pad "2" smd rect
			(at 0 1.397 270)
			(size 0.762 0.889)
			(layers "B.Cu" "B.Mask" "B.Paste")
			(net "P3V3_STBY_P1V5_LAN_I210")
		)
		(zone
			(layer "B.Cu")
			(hatch none 0.5)
			(connect_pads
				(clearance 0)
			)
			(min_thickness 0.25)
			(keepout
				(tracks not_allowed)
				(vias allowed)
				(pads allowed)
				(copperpour not_allowed)
				(footprints allowed)
			)
			(placement
				(enabled no)
				(sheetname "")
			)
			(fill
				(thermal_gap 0.5)
				(thermal_bridge_width 0.5)
				(island_removal_mode 0)
			)
			(polygon
				(pts
					(xy 477.3676 -36.6522) (xy 476.8596 -36.6522) (xy 476.8596 -35.8902) (xy 477.3676 -35.8902)
				)
			)
		)
		(zone
			(layer "B.Cu")
			(hatch none 0.5)
			(connect_pads
				(clearance 0)
			)
			(min_thickness 0.25)
			(keepout
				(tracks allowed)
				(vias not_allowed)
				(pads allowed)
				(copperpour not_allowed)
				(footprints allowed)
			)
			(placement
				(enabled no)
				(sheetname "")
			)
			(fill
				(thermal_gap 0.5)
				(thermal_bridge_width 0.5)
				(island_removal_mode 0)
			)
			(polygon
				(pts
					(xy 477.3676 -35.8902) (xy 476.8596 -35.8902) (xy 476.8596 -36.6522) (xy 477.3676 -36.6522)
				)
			)
		)
	)
	(footprint ""
		(layer "B.Cu")
		(at 498.6528 -151.9174)
		(property "Reference" "R1L8"
			(at 0 0 0)
			(layer "B.SilkS")
			(hide yes)
			(effects
				(font
					(size 1.27 1.27)
				)
				(justify mirror)
			)
		)
		(property "Value" ""
			(at 0 0 0)
			(layer "B.Fab")
			(effects
				(font
					(size 1.27 1.27)
				)
				(justify mirror)
			)
		)
		(duplicate_pad_numbers_are_jumpers no)
		(fp_poly
			(pts
				(xy 0.2794 -0.1016) (xy -0.2794 -0.1016) (xy -0.2794 0.9906) (xy 0.2794 0.9906)
			)
			(stroke
				(width 0)
				(type default)
			)
			(fill no)
			(layer "B.CrtYd")
		)
		(fp_line
			(start -0.2794 -0.1016)
			(end 0.2794 -0.1016)
			(stroke
				(width 0.1)
				(type default)
			)
			(layer "B.Fab")
		)
		(fp_line
			(start -0.2794 0.9906)
			(end -0.2794 -0.1016)
			(stroke
				(width 0.1)
				(type default)
			)
			(layer "B.Fab")
		)
		(fp_line
			(start 0.2794 -0.1016)
			(end 0.2794 0.9906)
			(stroke
				(width 0.1)
				(type default)
			)
			(layer "B.Fab")
		)
		(fp_line
			(start 0.2794 0.9906)
			(end -0.2794 0.9906)
			(stroke
				(width 0.1)
				(type default)
			)
			(layer "B.Fab")
		)
		(pad "1" smd rect
			(at 0 0 180)
			(size 0.508 0.508)
			(layers "B.Cu" "B.Mask" "B.Paste")
			(net "P5V_STBY")
		)
		(pad "2" smd rect
			(at 0 0.889 180)
			(size 0.508 0.508)
			(layers "B.Cu" "B.Mask" "B.Paste")
			(net "FP_ID_LED_XOR_R")
		)
		(zone
			(layer "B.Cu")
			(hatch none 0.5)
			(connect_pads
				(clearance 0)
			)
			(min_thickness 0.25)
			(keepout
				(tracks allowed)
				(vias not_allowed)
				(pads allowed)
				(copperpour not_allowed)
				(footprints allowed)
			)
			(placement
				(enabled no)
				(sheetname "")
			)
			(fill
				(thermal_gap 0.5)
				(thermal_bridge_width 0.5)
				(island_removal_mode 0)
			)
			(polygon
				(pts
					(xy 498.9068 -151.6634) (xy 498.3988 -151.6634) (xy 498.3988 -151.2824) (xy 498.9068 -151.2824)
				)
			)
		)
		(zone
			(layer "B.Cu")
			(hatch none 0.5)
			(connect_pads
				(clearance 0)
			)
			(min_thickness 0.25)
			(keepout
				(tracks not_allowed)
				(vias allowed)
				(pads allowed)
				(copperpour not_allowed)
				(footprints allowed)
			)
			(placement
				(enabled no)
				(sheetname "")
			)
			(fill
				(thermal_gap 0.5)
				(thermal_bridge_width 0.5)
				(island_removal_mode 0)
			)
			(polygon
				(pts
					(xy 498.9068 -151.2824) (xy 498.3988 -151.2824) (xy 498.3988 -151.6634) (xy 498.9068 -151.6634)
				)
			)
		)
	)
)
